# BARRELEYE_G2-MB-PVT-X04-HW-BOM-X26_20180122_Final.xls.xlsx — Summary (bom)
| PLATFORM SOURCING AND PSL COMPLIANCE |  |  |  |  |  |  |  |  |  |
| Platform Name: |  |  |  |  |  |  |  |  |  |
| REVISION HISTORY |  |  |  |  |  |  |  |  |  |
| BOM Revision: | ECR # | Revision Description | Originator | Date |  |  |  |  |  |
| X17 |  | DVT |  | 42907 |  |  |  |  |  |
| X26 |  |  |  | 43122 |  |  |  |  |  |
| Commodity Sourcing | # of components (X00 BOM) | % of Total | # of components (X01 BOM) | % of Total | # of components (X02 BOM) | % of Total | # of components (RTS) | % of Total | Risk Mitigation Plans in Place |
| Sole Source |  |  |  |  | 0 | 0 |  |  |  |
| Single Source |  |  |  |  | 94 | 0.2070484581 |  |  |  |
| Multiple |  |  |  |  | 360 | 0.7929515419 |  |  | NA |
| Total |  |  |  |  | 454 | 1 |  |  | NA |
|  |  | # of components | # of components aligned with Customer PSL* | % PSL alignment |  |  |  |  |  |
| Class 1 (Customer Managed) |  |  |  |  |  |  |  |  |  |
| Class 2 (ODM Managed to Customer PSL) |  |  |  |  |  |  |  |  |  |
| All other components(ODM Managed to ODM PSL) |  |  |  |  |  |  |  |  |  |
| *RFQ and/or Contract will list requirements for complying with Customer's PSL |  |  |  |  |  |  |  |  |  |
| Reference for quotation |  |  |  |  |  |  |  |  |  |
